(kicad_pcb
	(version 20260206)
	(generator "pcbnew")
	(generator_version "10.0")
	(general
		(thickness 1.6)
		(legacy_teardrops no)
	)
	(paper "A4")
	(title_block
		(title "Bryce Canyon_F.DPB_16315-1-OCP.brd")
		(comment 1 "Bryce Canyon / footprints 601-607 of 2223")
	)
	(layers
		(0 "F.Cu" signal "TOP")
		(4 "In1.Cu" signal "L2GND")
		(6 "In2.Cu" signal "L3")
		(8 "In3.Cu" signal "L4GND")
		(10 "In4.Cu" signal "L5")
		(12 "In5.Cu" signal "L6VCC")
		(14 "In6.Cu" signal "L7VCC")
		(16 "In7.Cu" signal "L8")
		(18 "In8.Cu" signal "L9GND")
		(20 "In9.Cu" signal "L10")
		(22 "In10.Cu" signal "L11GND")
		(2 "B.Cu" signal "BOTTOM")
		(9 "F.Adhes" user "F.Adhesive")
		(11 "B.Adhes" user "B.Adhesive")
		(13 "F.Paste" user "Package Geometry/Pastemask Top")
		(15 "B.Paste" user "Package Geometry/Pastemask Bottom")
		(5 "F.SilkS" user "Ref Des/Silkscreen Top")
		(7 "B.SilkS" user "Ref Des/Silkscreen Bottom")
		(1 "F.Mask" user "Board Geometry/Soldermask Top")
		(3 "B.Mask" user "Board Geometry/Soldermask Bottom")
		(17 "Dwgs.User" user "User.Drawings")
		(19 "Cmts.User" user "User.Comments")
		(21 "Eco1.User" user "User.Eco1")
		(23 "Eco2.User" user "User.Eco2")
		(25 "Edge.Cuts" user "Board Geometry/Outline")
		(27 "Margin" user)
		(31 "F.CrtYd" user "Package Geometry/Place Bound Top")
		(29 "B.CrtYd" user "Package Geometry/Place Bound Bottom")
		(35 "F.Fab" user "Ref Des/Assembly Top")
		(33 "B.Fab" user "Ref Des/Assembly Bottom")
	)
	(footprint ""
		(layer "F.Cu")
		(at 86.096348 -163.580318 90)
		(property "Reference" "R464"
			(at 0 0 90)
			(layer "F.SilkS")
			(hide yes)
			(effects
				(font
					(size 1.27 1.27)
				)
			)
		)
		(property "Value" "4K7R2J-2-GP"
			(at 0.064008 -3.993896 90)
			(unlocked yes)
			(layer "F.Fab")
			(hide yes)
			(effects
				(font
					(size 1.016 1.016)
					(thickness 0.1524)
				)
			)
		)
		(property "Device Type" "R402H16"
			(at 0.064008 -5.517896 90)
			(unlocked yes)
			(layer "F.Fab")
			(hide yes)
			(effects
				(font
					(size 1.016 1.016)
					(thickness 0.1524)
				)
			)
		)
		(duplicate_pad_numbers_are_jumpers no)
		(fp_line
			(start 0.508 -0.9398)
			(end -0.508 -0.9398)
			(stroke
				(width 0.1524)
				(type default)
			)
			(layer "F.SilkS")
		)
		(fp_line
			(start -0.508 -0.9398)
			(end -0.508 0.9398)
			(stroke
				(width 0.1524)
				(type default)
			)
			(layer "F.SilkS")
		)
		(fp_rect
			(start -0.508 0.9398)
			(end 0.508 -0.9398)
			(stroke
				(width 0)
				(type default)
			)
			(fill no)
			(layer "F.CrtYd")
		)
		(fp_rect
			(start -0.508 0.9398)
			(end 0.508 -0.9398)
			(stroke
				(width 0)
				(type default)
			)
			(fill no)
			(layer "F.Fab")
		)
		(pad "1" smd custom
			(at 0 -0.4445 90)
			(size 0.1397 0.1397)
			(layers "F.Cu" "F.Mask" "F.Paste")
			(net "SW_PWR_R_HDD14")
			(options
				(clearance outline)
				(anchor circle)
			)
			(primitives
				(gr_poly
					(pts
						(arc
							(start -0.1778 -0.2794)
							(mid -0.249642 -0.249642)
							(end -0.2794 -0.1778)
						)
						(arc
							(start -0.2794 0.1778)
							(mid -0.249642 0.249642)
							(end -0.1778 0.2794)
						)
						(arc
							(start 0.1778 0.2794)
							(mid 0.249642 0.249642)
							(end 0.2794 0.1778)
						)
						(arc
							(start 0.2794 -0.1778)
							(mid 0.249642 -0.249642)
							(end 0.1778 -0.2794)
						)
					)
					(width 0)
					(fill yes)
				)
			)
		)
		(pad "2" smd custom
			(at 0 0.4445 90)
			(size 0.1397 0.1397)
			(layers "F.Cu" "F.Mask" "F.Paste")
			(net "GND")
			(options
				(clearance outline)
				(anchor circle)
			)
			(primitives
				(gr_poly
					(pts
						(arc
							(start -0.1778 -0.2794)
							(mid -0.249642 -0.249642)
							(end -0.2794 -0.1778)
						)
						(arc
							(start -0.2794 0.1778)
							(mid -0.249642 0.249642)
							(end -0.1778 0.2794)
						)
						(arc
							(start 0.1778 0.2794)
							(mid 0.249642 0.249642)
							(end 0.2794 0.1778)
						)
						(arc
							(start 0.2794 -0.1778)
							(mid 0.249642 -0.249642)
							(end 0.1778 -0.2794)
						)
					)
					(width 0)
					(fill yes)
				)
			)
		)
	)
	(footprint ""
		(layer "F.Cu")
		(at 264.541 -272.288 180)
		(property "Reference" "R109"
			(at 0 0 180)
			(layer "F.SilkS")
			(hide yes)
			(effects
				(font
					(size 1.27 1.27)
				)
			)
		)
		(property "Value" "4K7R2F-GP"
			(at 0.064008 -3.993896 180)
			(unlocked yes)
			(layer "F.Fab")
			(hide yes)
			(effects
				(font
					(size 1.016 1.016)
					(thickness 0.1524)
				)
			)
		)
		(property "Device Type" "R402H16"
			(at 0.064008 -5.517896 180)
			(unlocked yes)
			(layer "F.Fab")
			(hide yes)
			(effects
				(font
					(size 1.016 1.016)
					(thickness 0.1524)
				)
			)
		)
		(duplicate_pad_numbers_are_jumpers no)
		(fp_line
			(start 0.508 -0.9398)
			(end -0.508 -0.9398)
			(stroke
				(width 0.1524)
				(type default)
			)
			(layer "F.SilkS")
		)
		(fp_line
			(start -0.508 -0.9398)
			(end -0.508 0.9398)
			(stroke
				(width 0.1524)
				(type default)
			)
			(layer "F.SilkS")
		)
		(fp_rect
			(start -0.508 0.9398)
			(end 0.508 -0.9398)
			(stroke
				(width 0)
				(type default)
			)
			(fill no)
			(layer "F.CrtYd")
		)
		(fp_rect
			(start -0.508 0.9398)
			(end 0.508 -0.9398)
			(stroke
				(width 0)
				(type default)
			)
			(fill no)
			(layer "F.Fab")
		)
		(pad "1" smd custom
			(at 0 -0.4445 180)
			(size 0.1397 0.1397)
			(layers "F.Cu" "F.Mask" "F.Paste")
			(net "P3V3_STBY_A")
			(options
				(clearance outline)
				(anchor circle)
			)
			(primitives
				(gr_poly
					(pts
						(arc
							(start -0.1778 -0.2794)
							(mid -0.249642 -0.249642)
							(end -0.2794 -0.1778)
						)
						(arc
							(start -0.2794 0.1778)
							(mid -0.249642 0.249642)
							(end -0.1778 0.2794)
						)
						(arc
							(start 0.1778 0.2794)
							(mid 0.249642 0.249642)
							(end 0.2794 0.1778)
						)
						(arc
							(start 0.2794 -0.1778)
							(mid 0.249642 -0.249642)
							(end 0.1778 -0.2794)
						)
					)
					(width 0)
					(fill yes)
				)
			)
		)
		(pad "2" smd custom
			(at 0 0.4445 180)
			(size 0.1397 0.1397)
			(layers "F.Cu" "F.Mask" "F.Paste")
			(net "IO_EXP0_HDD_FAULT_A2")
			(options
				(clearance outline)
				(anchor circle)
			)
			(primitives
				(gr_poly
					(pts
						(arc
							(start -0.1778 -0.2794)
							(mid -0.249642 -0.249642)
							(end -0.2794 -0.1778)
						)
						(arc
							(start -0.2794 0.1778)
							(mid -0.249642 0.249642)
							(end -0.1778 0.2794)
						)
						(arc
							(start 0.1778 0.2794)
							(mid 0.249642 0.249642)
							(end 0.2794 0.1778)
						)
						(arc
							(start 0.2794 -0.1778)
							(mid 0.249642 -0.249642)
							(end 0.1778 -0.2794)
						)
					)
					(width 0)
					(fill yes)
				)
			)
		)
	)
	(footprint ""
		(layer "F.Cu")
		(at 231.913684 -388.72287 90)
		(property "Reference" "C102"
			(at 0 0 90)
			(layer "F.SilkS")
			(hide yes)
			(effects
				(font
					(size 1.27 1.27)
				)
			)
		)
		(property "Value" "SCD1U16V2KX-3GP"
			(at 1.1811 -2.7051 90)
			(unlocked yes)
			(layer "F.Fab")
			(hide yes)
			(effects
				(font
					(size 1.016 1.016)
					(thickness 0.1524)
				)
			)
		)
		(property "Device Type" "C402H22"
			(at 1.1811 -4.2291 90)
			(unlocked yes)
			(layer "F.Fab")
			(hide yes)
			(effects
				(font
					(size 1.016 1.016)
					(thickness 0.1524)
				)
			)
		)
		(duplicate_pad_numbers_are_jumpers no)
		(fp_rect
			(start -0.4318 0.9525)
			(end 0.4318 -0.9525)
			(stroke
				(width 0)
				(type default)
			)
			(fill no)
			(layer "F.CrtYd")
		)
		(fp_rect
			(start -0.4318 0.9525)
			(end 0.4318 -0.9525)
			(stroke
				(width 0)
				(type default)
			)
			(fill no)
			(layer "F.Fab")
		)
		(pad "1" smd custom
			(at 0 -0.4445 90)
			(size 0.1524 0.1524)
			(layers "F.Cu" "F.Mask" "F.Paste")
			(net "P3V3_IN_BIAS")
			(options
				(clearance outline)
				(anchor circle)
			)
			(primitives
				(gr_poly
					(pts
						(arc
							(start 0.3048 -0.2032)
							(mid 0.275042 -0.275042)
							(end 0.2032 -0.3048)
						)
						(arc
							(start -0.2032 -0.3048)
							(mid -0.275042 -0.275042)
							(end -0.3048 -0.2032)
						)
						(arc
							(start -0.3048 0.2032)
							(mid -0.275042 0.275042)
							(end -0.2032 0.3048)
						)
						(arc
							(start 0.2032 0.3048)
							(mid 0.275042 0.275042)
							(end 0.3048 0.2032)
						)
					)
					(width 0)
					(fill yes)
				)
			)
		)
		(pad "2" smd custom
			(at 0 0.4445 90)
			(size 0.1524 0.1524)
			(layers "F.Cu" "F.Mask" "F.Paste")
			(net "GND")
			(options
				(clearance outline)
				(anchor circle)
			)
			(primitives
				(gr_poly
					(pts
						(arc
							(start 0.3048 -0.2032)
							(mid 0.275042 -0.275042)
							(end 0.2032 -0.3048)
						)
						(arc
							(start -0.2032 -0.3048)
							(mid -0.275042 -0.275042)
							(end -0.3048 -0.2032)
						)
						(arc
							(start -0.3048 0.2032)
							(mid -0.275042 0.275042)
							(end -0.2032 0.3048)
						)
						(arc
							(start 0.2032 0.3048)
							(mid 0.275042 0.275042)
							(end 0.3048 0.2032)
						)
					)
					(width 0)
					(fill yes)
				)
			)
		)
	)
	(footprint ""
		(layer "F.Cu")
		(at 374.00992 -127.703072 180)
		(property "Reference" "Q247"
			(at 0 0 180)
			(layer "F.SilkS")
			(hide yes)
			(effects
				(font
					(size 1.27 1.27)
				)
			)
		)
		(property "Value" "2N7002K-2-GP"
			(at 0.127 -8.9662 180)
			(unlocked yes)
			(layer "F.Fab")
			(hide yes)
			(effects
				(font
					(size 1.016 1.016)
					(thickness 0.1524)
				)
			)
		)
		(property "Device Type" "SOT23DGS2D4H44"
			(at 0.127 -10.4902 180)
			(unlocked yes)
			(layer "F.Fab")
			(hide yes)
			(effects
				(font
					(size 1.016 1.016)
					(thickness 0.1524)
				)
			)
		)
		(duplicate_pad_numbers_are_jumpers no)
		(fp_line
			(start 1.651 1.778)
			(end 1.651 -1.778)
			(stroke
				(width 0.1524)
				(type default)
			)
			(layer "F.SilkS")
		)
		(fp_line
			(start 1.651 -1.778)
			(end -1.651 -1.778)
			(stroke
				(width 0.1524)
				(type default)
			)
			(layer "F.SilkS")
		)
		(fp_line
			(start -1.651 1.778)
			(end 1.651 1.778)
			(stroke
				(width 0.1524)
				(type default)
			)
			(layer "F.SilkS")
		)
		(fp_line
			(start -1.651 -1.778)
			(end -1.651 1.778)
			(stroke
				(width 0.1524)
				(type default)
			)
			(layer "F.SilkS")
		)
		(fp_poly
			(pts
				(xy -1.778 1.8796) (xy -1.778 -1.8796) (xy 1.778 -1.8796) (xy 1.778 1.8796)
			)
			(stroke
				(width 0)
				(type default)
			)
			(fill no)
			(layer "F.CrtYd")
		)
		(fp_poly
			(pts
				(xy -1.778 1.8796) (xy -1.778 -1.8796) (xy 1.778 -1.8796) (xy 1.778 1.8796)
			)
			(stroke
				(width 0)
				(type default)
			)
			(fill no)
			(layer "F.Fab")
		)
		(pad "D" smd custom
			(at 0 -0.9525 180)
			(size 0.1905 0.1905)
			(layers "F.Cu" "F.Mask" "F.Paste")
			(net "FLT_HDD20_N")
			(options
				(clearance outline)
				(anchor circle)
			)
			(primitives
				(gr_poly
					(pts
						(arc
							(start -0.1778 0.5715)
							(mid -0.321484 0.511984)
							(end -0.381 0.3683)
						)
						(arc
							(start -0.381 -0.3683)
							(mid -0.321484 -0.511984)
							(end -0.1778 -0.5715)
						)
						(arc
							(start 0.1778 -0.5715)
							(mid 0.321484 -0.511984)
							(end 0.381 -0.3683)
						)
						(arc
							(start 0.381 0.3683)
							(mid 0.321484 0.511984)
							(end 0.1778 0.5715)
						)
					)
					(width 0)
					(fill yes)
				)
			)
		)
		(pad "G" smd custom
			(at -0.98425 0.9525 180)
			(size 0.1905 0.1905)
			(layers "F.Cu" "F.Mask" "F.Paste")
			(net "DRIVE_A_20_FLT_LED")
			(options
				(clearance outline)
				(anchor circle)
			)
			(primitives
				(gr_poly
					(pts
						(arc
							(start -0.1778 0.5715)
							(mid -0.321484 0.511984)
							(end -0.381 0.3683)
						)
						(arc
							(start -0.381 -0.3683)
							(mid -0.321484 -0.511984)
							(end -0.1778 -0.5715)
						)
						(arc
							(start 0.1778 -0.5715)
							(mid 0.321484 -0.511984)
							(end 0.381 -0.3683)
						)
						(arc
							(start 0.381 0.3683)
							(mid 0.321484 0.511984)
							(end 0.1778 0.5715)
						)
					)
					(width 0)
					(fill yes)
				)
			)
		)
		(pad "S" smd custom
			(at 0.98425 0.9525 180)
			(size 0.1905 0.1905)
			(layers "F.Cu" "F.Mask" "F.Paste")
			(net "GND")
			(options
				(clearance outline)
				(anchor circle)
			)
			(primitives
				(gr_poly
					(pts
						(arc
							(start -0.1778 0.5715)
							(mid -0.321484 0.511984)
							(end -0.381 0.3683)
						)
						(arc
							(start -0.381 -0.3683)
							(mid -0.321484 -0.511984)
							(end -0.1778 -0.5715)
						)
						(arc
							(start 0.1778 -0.5715)
							(mid 0.321484 -0.511984)
							(end 0.381 -0.3683)
						)
						(arc
							(start 0.381 0.3683)
							(mid 0.321484 0.511984)
							(end 0.1778 0.5715)
						)
					)
					(width 0)
					(fill yes)
				)
			)
		)
	)
	(footprint ""
		(layer "F.Cu")
		(at 368.8588 -145.8214 180)
		(property "Reference" "R1088"
			(at 0 0 180)
			(layer "F.SilkS")
			(hide yes)
			(effects
				(font
					(size 1.27 1.27)
				)
			)
		)
		(property "Value" "11KR2F-L-GP"
			(at 0.064008 -3.993896 180)
			(unlocked yes)
			(layer "F.Fab")
			(hide yes)
			(effects
				(font
					(size 1.016 1.016)
					(thickness 0.1524)
				)
			)
		)
		(property "Device Type" "R402H16"
			(at 0.064008 -5.517896 180)
			(unlocked yes)
			(layer "F.Fab")
			(hide yes)
			(effects
				(font
					(size 1.016 1.016)
					(thickness 0.1524)
				)
			)
		)
		(duplicate_pad_numbers_are_jumpers no)
		(fp_line
			(start 0.508 -0.9398)
			(end -0.508 -0.9398)
			(stroke
				(width 0.1524)
				(type default)
			)
			(layer "F.SilkS")
		)
		(fp_line
			(start -0.508 -0.9398)
			(end -0.508 0.9398)
			(stroke
				(width 0.1524)
				(type default)
			)
			(layer "F.SilkS")
		)
		(fp_rect
			(start -0.508 0.9398)
			(end 0.508 -0.9398)
			(stroke
				(width 0)
				(type default)
			)
			(fill no)
			(layer "F.CrtYd")
		)
		(fp_rect
			(start -0.508 0.9398)
			(end 0.508 -0.9398)
			(stroke
				(width 0)
				(type default)
			)
			(fill no)
			(layer "F.Fab")
		)
		(pad "1" smd custom
			(at 0 -0.4445 180)
			(size 0.1397 0.1397)
			(layers "F.Cu" "F.Mask" "F.Paste")
			(net "MB1_P12V_PWGIN_R")
			(options
				(clearance outline)
				(anchor circle)
			)
			(primitives
				(gr_poly
					(pts
						(arc
							(start -0.1778 -0.2794)
							(mid -0.249642 -0.249642)
							(end -0.2794 -0.1778)
						)
						(arc
							(start -0.2794 0.1778)
							(mid -0.249642 0.249642)
							(end -0.1778 0.2794)
						)
						(arc
							(start 0.1778 0.2794)
							(mid 0.249642 0.249642)
							(end 0.2794 0.1778)
						)
						(arc
							(start 0.2794 -0.1778)
							(mid 0.249642 -0.249642)
							(end 0.1778 -0.2794)
						)
					)
					(width 0)
					(fill yes)
				)
			)
		)
		(pad "2" smd custom
			(at 0 0.4445 180)
			(size 0.1397 0.1397)
			(layers "F.Cu" "F.Mask" "F.Paste")
			(net "AGND_CURRENT_MONOB")
			(options
				(clearance outline)
				(anchor circle)
			)
			(primitives
				(gr_poly
					(pts
						(arc
							(start -0.1778 -0.2794)
							(mid -0.249642 -0.249642)
							(end -0.2794 -0.1778)
						)
						(arc
							(start -0.2794 0.1778)
							(mid -0.249642 0.249642)
							(end -0.1778 0.2794)
						)
						(arc
							(start 0.1778 0.2794)
							(mid 0.249642 0.249642)
							(end 0.2794 0.1778)
						)
						(arc
							(start 0.2794 -0.1778)
							(mid 0.249642 -0.249642)
							(end 0.1778 -0.2794)
						)
					)
					(width 0)
					(fill yes)
				)
			)
		)
	)
	(footprint ""
		(layer "F.Cu")
		(at 55.790846 -74.462894 180)
		(property "Reference" "C372"
			(at 0 0 180)
			(layer "F.SilkS")
			(hide yes)
			(effects
				(font
					(size 1.27 1.27)
				)
			)
		)
		(property "Value" "SC1U25V3KX-GP"
			(at 0 -2.8194 180)
			(unlocked yes)
			(layer "F.Fab")
			(hide yes)
			(effects
				(font
					(size 1.016 1.016)
					(thickness 0.1524)
				)
			)
		)
		(property "Device Type" "C603H36"
			(at 0 -4.3434 180)
			(unlocked yes)
			(layer "F.Fab")
			(hide yes)
			(effects
				(font
					(size 1.016 1.016)
					(thickness 0.1524)
				)
			)
		)
		(duplicate_pad_numbers_are_jumpers no)
		(fp_line
			(start 0.508 0)
			(end -0.508 0)
			(stroke
				(width 0.2032)
				(type default)
			)
			(layer "F.SilkS")
		)
		(fp_rect
			(start -0.5842 1.3335)
			(end 0.5842 -1.3335)
			(stroke
				(width 0)
				(type default)
			)
			(fill no)
			(layer "F.CrtYd")
		)
		(fp_rect
			(start -0.5842 1.3335)
			(end 0.5842 -1.3335)
			(stroke
				(width 0)
				(type default)
			)
			(fill no)
			(layer "F.Fab")
		)
		(pad "1" smd custom
			(at 0 -0.762 180)
			(size 0.2159 0.2159)
			(layers "F.Cu" "F.Mask" "F.Paste")
			(net "P12V_HDD25")
			(options
				(clearance outline)
				(anchor circle)
			)
			(primitives
				(gr_poly
					(pts
						(arc
							(start -0.3302 -0.4318)
							(mid -0.402042 -0.402042)
							(end -0.4318 -0.3302)
						)
						(arc
							(start -0.4318 0.3302)
							(mid -0.402042 0.402042)
							(end -0.3302 0.4318)
						)
						(arc
							(start 0.3302 0.4318)
							(mid 0.402042 0.402042)
							(end 0.4318 0.3302)
						)
						(arc
							(start 0.4318 -0.3302)
							(mid 0.402042 -0.402042)
							(end 0.3302 -0.4318)
						)
					)
					(width 0)
					(fill yes)
				)
			)
		)
		(pad "2" smd custom
			(at 0 0.762 180)
			(size 0.2159 0.2159)
			(layers "F.Cu" "F.Mask" "F.Paste")
			(net "GND")
			(options
				(clearance outline)
				(anchor circle)
			)
			(primitives
				(gr_poly
					(pts
						(arc
							(start -0.3302 -0.4318)
							(mid -0.402042 -0.402042)
							(end -0.4318 -0.3302)
						)
						(arc
							(start -0.4318 0.3302)
							(mid -0.402042 0.402042)
							(end -0.3302 0.4318)
						)
						(arc
							(start 0.3302 0.4318)
							(mid 0.402042 0.402042)
							(end 0.4318 0.3302)
						)
						(arc
							(start 0.4318 -0.3302)
							(mid 0.402042 -0.402042)
							(end 0.3302 -0.4318)
						)
					)
					(width 0)
					(fill yes)
				)
			)
		)
	)
	(footprint ""
		(layer "F.Cu")
		(at 240.538 -394.3858 -90)
		(property "Reference" "R1162"
			(at 0 0 270)
			(layer "F.SilkS")
			(hide yes)
			(effects
				(font
					(size 1.27 1.27)
				)
			)
		)
		(property "Value" "100KR2F-L1-GP"
			(at 0.064008 -3.993896 270)
			(unlocked yes)
			(layer "F.Fab")
			(hide yes)
			(effects
				(font
					(size 1.016 1.016)
					(thickness 0.1524)
				)
			)
		)
		(property "Device Type" "R402H16"
			(at 0.064008 -5.517896 270)
			(unlocked yes)
			(layer "F.Fab")
			(hide yes)
			(effects
				(font
					(size 1.016 1.016)
					(thickness 0.1524)
				)
			)
		)
		(duplicate_pad_numbers_are_jumpers no)
		(fp_line
			(start -0.508 -0.9398)
			(end -0.508 0.9398)
			(stroke
				(width 0.1524)
				(type default)
			)
			(layer "F.SilkS")
		)
		(fp_line
			(start 0.508 -0.9398)
			(end -0.508 -0.9398)
			(stroke
				(width 0.1524)
				(type default)
			)
			(layer "F.SilkS")
		)
		(fp_rect
			(start -0.508 0.9398)
			(end 0.508 -0.9398)
			(stroke
				(width 0)
				(type default)
			)
			(fill no)
			(layer "F.CrtYd")
		)
		(fp_rect
			(start -0.508 0.9398)
			(end 0.508 -0.9398)
			(stroke
				(width 0)
				(type default)
			)
			(fill no)
			(layer "F.Fab")
		)
		(pad "1" smd custom
			(at 0 -0.4445 270)
			(size 0.1397 0.1397)
			(layers "F.Cu" "F.Mask" "F.Paste")
			(net "MB3_VCAP_R")
			(options
				(clearance outline)
				(anchor circle)
			)
			(primitives
				(gr_poly
					(pts
						(arc
							(start -0.1778 -0.2794)
							(mid -0.249642 -0.249642)
							(end -0.2794 -0.1778)
						)
						(arc
							(start -0.2794 0.1778)
							(mid -0.249642 0.249642)
							(end -0.1778 0.2794)
						)
						(arc
							(start 0.1778 0.2794)
							(mid 0.249642 0.249642)
							(end 0.2794 0.1778)
						)
						(arc
							(start 0.2794 -0.1778)
							(mid 0.249642 -0.249642)
							(end 0.1778 -0.2794)
						)
					)
					(width 0)
					(fill yes)
				)
			)
		)
		(pad "2" smd custom
			(at 0 0.4445 270)
			(size 0.1397 0.1397)
			(layers "F.Cu" "F.Mask" "F.Paste")
			(net "MB3_ISET_R")
			(options
				(clearance outline)
				(anchor circle)
			)
			(primitives
				(gr_poly
					(pts
						(arc
							(start -0.1778 -0.2794)
							(mid -0.249642 -0.249642)
							(end -0.2794 -0.1778)
						)
						(arc
							(start -0.2794 0.1778)
							(mid -0.249642 0.249642)
							(end -0.1778 0.2794)
						)
						(arc
							(start 0.1778 0.2794)
							(mid 0.249642 0.249642)
							(end 0.2794 0.1778)
						)
						(arc
							(start 0.2794 -0.1778)
							(mid 0.249642 -0.249642)
							(end 0.1778 -0.2794)
						)
					)
					(width 0)
					(fill yes)
				)
			)
		)
	)
)
